(kicad_pcb
	(version 20260206)
	(generator "pcbnew")
	(generator_version "10.0")
	(general
		(thickness 1.6)
		(legacy_teardrops no)
	)
	(paper "A4")
	(title_block
		(title "04192023_DAF0TMB3IC0_F0TG_MB_C_brd_V02_OCP.brd")
		(comment 1 "Grand Teton / footprints 5871-5879 of 8354")
	)
	(layers
		(0 "F.Cu" signal "TOP")
		(4 "In1.Cu" signal "GND")
		(6 "In2.Cu" signal "IN1")
		(8 "In3.Cu" signal "GND1")
		(10 "In4.Cu" signal "IN2")
		(12 "In5.Cu" signal "GND2")
		(14 "In6.Cu" signal "IN3")
		(16 "In7.Cu" signal "GND3")
		(18 "In8.Cu" signal "VCC")
		(20 "In9.Cu" signal "VCC1")
		(22 "In10.Cu" signal "GND4")
		(24 "In11.Cu" signal "IN4")
		(26 "In12.Cu" signal "GND5")
		(28 "In13.Cu" signal "IN5")
		(30 "In14.Cu" signal "GND6")
		(32 "In15.Cu" signal "IN6")
		(34 "In16.Cu" signal "GND7")
		(2 "B.Cu" signal "BOTTOM")
		(9 "F.Adhes" user "F.Adhesive")
		(11 "B.Adhes" user "B.Adhesive")
		(13 "F.Paste" user "Package Geometry/Pastemask Top")
		(15 "B.Paste" user "Package Geometry/Pastemask Bottom")
		(5 "F.SilkS" user "Ref Des/Silkscreen Top")
		(7 "B.SilkS" user "Ref Des/Silkscreen Bottom")
		(1 "F.Mask" user "Board Geometry/Soldermask Top")
		(3 "B.Mask" user "Board Geometry/Soldermask Bottom")
		(17 "Dwgs.User" user "User.Drawings")
		(19 "Cmts.User" user "User.Comments")
		(21 "Eco1.User" user "User.Eco1")
		(23 "Eco2.User" user "User.Eco2")
		(25 "Edge.Cuts" user "Board Geometry/Outline")
		(27 "Margin" user)
		(31 "F.CrtYd" user "Package Geometry/Place Bound Top")
		(29 "B.CrtYd" user "Package Geometry/Place Bound Bottom")
		(35 "F.Fab" user "Ref Des/Assembly Top")
		(33 "B.Fab" user "Ref Des/Assembly Bottom")
	)
	(footprint ""
		(layer "B.Cu")
		(at 307.118258 -396.393162 -90)
		(property "Reference" "C558"
			(at 0 0 90)
			(layer "B.SilkS")
			(hide yes)
			(effects
				(font
					(size 1.27 1.27)
				)
				(justify mirror)
			)
		)
		(property "Value" ""
			(at 0 0 90)
			(layer "B.Fab")
			(effects
				(font
					(size 1.27 1.27)
				)
				(justify mirror)
			)
		)
		(duplicate_pad_numbers_are_jumpers no)
		(fp_line
			(start -0.299974 0.150114)
			(end 0.299974 0.150114)
			(stroke
				(width 0.1)
				(type default)
			)
			(layer "B.Fab")
		)
		(fp_line
			(start 0.299974 0.150114)
			(end 0.299974 -0.150114)
			(stroke
				(width 0.1)
				(type default)
			)
			(layer "B.Fab")
		)
		(fp_line
			(start -0.299974 -0.150114)
			(end -0.299974 0.150114)
			(stroke
				(width 0.1)
				(type default)
			)
			(layer "B.Fab")
		)
		(fp_line
			(start 0.299974 -0.150114)
			(end -0.299974 -0.150114)
			(stroke
				(width 0.1)
				(type default)
			)
			(layer "B.Fab")
		)
		(pad "1" smd rect
			(at 0.2667 0 90)
			(size 0.3048 0.381)
			(layers "B.Cu" "B.Mask" "B.Paste")
			(net "P0V9_CPU0_RT0_2A")
		)
		(pad "2" smd rect
			(at -0.2667 0 90)
			(size 0.3048 0.381)
			(layers "B.Cu" "B.Mask" "B.Paste")
			(net "GND")
		)
	)
	(footprint ""
		(layer "B.Cu")
		(at 98.454464 -266.640564)
		(property "Reference" "C2659"
			(at 0 0 0)
			(layer "B.SilkS")
			(hide yes)
			(effects
				(font
					(size 1.27 1.27)
				)
				(justify mirror)
			)
		)
		(property "Value" ""
			(at 0 0 0)
			(layer "B.Fab")
			(effects
				(font
					(size 1.27 1.27)
				)
				(justify mirror)
			)
		)
		(duplicate_pad_numbers_are_jumpers no)
		(fp_line
			(start -0.7874 -0.4064)
			(end -0.7874 0.4064)
			(stroke
				(width 0.1524)
				(type default)
			)
			(layer "B.SilkS")
		)
		(fp_line
			(start -0.7874 0.4064)
			(end 0.7874 0.4064)
			(stroke
				(width 0.1524)
				(type default)
			)
			(layer "B.SilkS")
		)
		(fp_line
			(start 0.7874 -0.4064)
			(end -0.7874 -0.4064)
			(stroke
				(width 0.1524)
				(type default)
			)
			(layer "B.SilkS")
		)
		(fp_line
			(start 0.7874 0.4064)
			(end 0.7874 -0.4064)
			(stroke
				(width 0.1524)
				(type default)
			)
			(layer "B.SilkS")
		)
		(fp_line
			(start -0.67945 -0.3048)
			(end -0.67945 0.3048)
			(stroke
				(width 0.1)
				(type default)
			)
			(layer "B.Fab")
		)
		(fp_line
			(start -0.67945 0.3048)
			(end -0.120396 0.3048)
			(stroke
				(width 0.1)
				(type default)
			)
			(layer "B.Fab")
		)
		(fp_line
			(start -0.12065 -0.3048)
			(end -0.67945 -0.3048)
			(stroke
				(width 0.1)
				(type default)
			)
			(layer "B.Fab")
		)
		(fp_line
			(start -0.12065 -0.2794)
			(end -0.12065 -0.3048)
			(stroke
				(width 0.1)
				(type default)
			)
			(layer "B.Fab")
		)
		(fp_line
			(start -0.120396 0.2794)
			(end 0.12065 0.2794)
			(stroke
				(width 0.1)
				(type default)
			)
			(layer "B.Fab")
		)
		(fp_line
			(start -0.120396 0.3048)
			(end -0.120396 0.2794)
			(stroke
				(width 0.1)
				(type default)
			)
			(layer "B.Fab")
		)
		(fp_line
			(start 0.12065 -0.305054)
			(end 0.12065 -0.2794)
			(stroke
				(width 0.1)
				(type default)
			)
			(layer "B.Fab")
		)
		(fp_line
			(start 0.12065 -0.2794)
			(end -0.12065 -0.2794)
			(stroke
				(width 0.1)
				(type default)
			)
			(layer "B.Fab")
		)
		(fp_line
			(start 0.12065 0.2794)
			(end 0.12065 0.3048)
			(stroke
				(width 0.1)
				(type default)
			)
			(layer "B.Fab")
		)
		(fp_line
			(start 0.12065 0.3048)
			(end 0.67945 0.3048)
			(stroke
				(width 0.1)
				(type default)
			)
			(layer "B.Fab")
		)
		(fp_line
			(start 0.67945 -0.305054)
			(end 0.12065 -0.305054)
			(stroke
				(width 0.1)
				(type default)
			)
			(layer "B.Fab")
		)
		(fp_line
			(start 0.67945 0.3048)
			(end 0.67945 -0.305054)
			(stroke
				(width 0.1)
				(type default)
			)
			(layer "B.Fab")
		)
		(pad "1" smd circle
			(at 0.40005 0 180)
			(size 0 0)
			(layers "B.Cu" "B.Mask" "B.Paste")
			(net "PVDD_33_S5")
		)
		(pad "2" smd circle
			(at -0.40005 0 180)
			(size 0 0)
			(layers "B.Cu" "B.Mask" "B.Paste")
			(net "GND")
		)
	)
	(footprint ""
		(layer "B.Cu")
		(at 134.262114 -33.834578 180)
		(property "Reference" "C6048"
			(at 0 0 0)
			(layer "B.SilkS")
			(hide yes)
			(effects
				(font
					(size 1.27 1.27)
				)
				(justify mirror)
			)
		)
		(property "Value" ""
			(at 0 0 0)
			(layer "B.Fab")
			(effects
				(font
					(size 1.27 1.27)
				)
				(justify mirror)
			)
		)
		(duplicate_pad_numbers_are_jumpers no)
		(fp_line
			(start 0.7874 0.4064)
			(end 0.7874 -0.4064)
			(stroke
				(width 0.1524)
				(type default)
			)
			(layer "B.SilkS")
		)
		(fp_line
			(start 0.7874 -0.4064)
			(end -0.7874 -0.4064)
			(stroke
				(width 0.1524)
				(type default)
			)
			(layer "B.SilkS")
		)
		(fp_line
			(start -0.7874 0.4064)
			(end 0.7874 0.4064)
			(stroke
				(width 0.1524)
				(type default)
			)
			(layer "B.SilkS")
		)
		(fp_line
			(start -0.7874 -0.4064)
			(end -0.7874 0.4064)
			(stroke
				(width 0.1524)
				(type default)
			)
			(layer "B.SilkS")
		)
		(fp_line
			(start 0.67945 0.3048)
			(end 0.67945 -0.305054)
			(stroke
				(width 0.1)
				(type default)
			)
			(layer "B.Fab")
		)
		(fp_line
			(start 0.67945 -0.305054)
			(end 0.12065 -0.305054)
			(stroke
				(width 0.1)
				(type default)
			)
			(layer "B.Fab")
		)
		(fp_line
			(start 0.12065 0.3048)
			(end 0.67945 0.3048)
			(stroke
				(width 0.1)
				(type default)
			)
			(layer "B.Fab")
		)
		(fp_line
			(start 0.12065 0.2794)
			(end 0.12065 0.3048)
			(stroke
				(width 0.1)
				(type default)
			)
			(layer "B.Fab")
		)
		(fp_line
			(start 0.12065 -0.2794)
			(end -0.12065 -0.2794)
			(stroke
				(width 0.1)
				(type default)
			)
			(layer "B.Fab")
		)
		(fp_line
			(start 0.12065 -0.305054)
			(end 0.12065 -0.2794)
			(stroke
				(width 0.1)
				(type default)
			)
			(layer "B.Fab")
		)
		(fp_line
			(start -0.120396 0.3048)
			(end -0.120396 0.2794)
			(stroke
				(width 0.1)
				(type default)
			)
			(layer "B.Fab")
		)
		(fp_line
			(start -0.120396 0.2794)
			(end 0.12065 0.2794)
			(stroke
				(width 0.1)
				(type default)
			)
			(layer "B.Fab")
		)
		(fp_line
			(start -0.12065 -0.2794)
			(end -0.12065 -0.3048)
			(stroke
				(width 0.1)
				(type default)
			)
			(layer "B.Fab")
		)
		(fp_line
			(start -0.12065 -0.3048)
			(end -0.67945 -0.3048)
			(stroke
				(width 0.1)
				(type default)
			)
			(layer "B.Fab")
		)
		(fp_line
			(start -0.67945 0.3048)
			(end -0.120396 0.3048)
			(stroke
				(width 0.1)
				(type default)
			)
			(layer "B.Fab")
		)
		(fp_line
			(start -0.67945 -0.3048)
			(end -0.67945 0.3048)
			(stroke
				(width 0.1)
				(type default)
			)
			(layer "B.Fab")
		)
		(pad "1" smd circle
			(at 0.40005 0)
			(size 0 0)
			(layers "B.Cu" "B.Mask" "B.Paste")
			(net "P3V3_AUX")
		)
		(pad "2" smd circle
			(at -0.40005 0)
			(size 0 0)
			(layers "B.Cu" "B.Mask" "B.Paste")
			(net "GND")
		)
	)
	(footprint ""
		(layer "B.Cu")
		(at 51.766978 -433.682902 90)
		(property "Reference" "R3498"
			(at 0 0 90)
			(layer "B.SilkS")
			(hide yes)
			(effects
				(font
					(size 1.27 1.27)
				)
				(justify mirror)
			)
		)
		(property "Value" ""
			(at 0 0 90)
			(layer "B.Fab")
			(effects
				(font
					(size 1.27 1.27)
				)
				(justify mirror)
			)
		)
		(duplicate_pad_numbers_are_jumpers no)
		(fp_line
			(start 0.7874 -0.4064)
			(end -0.7874 -0.4064)
			(stroke
				(width 0.1524)
				(type default)
			)
			(layer "B.SilkS")
		)
		(fp_line
			(start -0.7874 -0.4064)
			(end -0.7874 0.4064)
			(stroke
				(width 0.1524)
				(type default)
			)
			(layer "B.SilkS")
		)
		(fp_line
			(start 0.7874 0.4064)
			(end 0.7874 -0.4064)
			(stroke
				(width 0.1524)
				(type default)
			)
			(layer "B.SilkS")
		)
		(fp_line
			(start -0.7874 0.4064)
			(end 0.7874 0.4064)
			(stroke
				(width 0.1524)
				(type default)
			)
			(layer "B.SilkS")
		)
		(fp_line
			(start 0.67945 -0.305054)
			(end 0.12065 -0.305054)
			(stroke
				(width 0.1)
				(type default)
			)
			(layer "B.Fab")
		)
		(fp_line
			(start 0.12065 -0.305054)
			(end 0.12065 -0.2794)
			(stroke
				(width 0.1)
				(type default)
			)
			(layer "B.Fab")
		)
		(fp_line
			(start -0.12065 -0.3048)
			(end -0.67945 -0.3048)
			(stroke
				(width 0.1)
				(type default)
			)
			(layer "B.Fab")
		)
		(fp_line
			(start -0.67945 -0.3048)
			(end -0.67945 0.3048)
			(stroke
				(width 0.1)
				(type default)
			)
			(layer "B.Fab")
		)
		(fp_line
			(start 0.12065 -0.2794)
			(end -0.12065 -0.2794)
			(stroke
				(width 0.1)
				(type default)
			)
			(layer "B.Fab")
		)
		(fp_line
			(start -0.12065 -0.2794)
			(end -0.12065 -0.3048)
			(stroke
				(width 0.1)
				(type default)
			)
			(layer "B.Fab")
		)
		(fp_line
			(start 0.12065 0.2794)
			(end 0.12065 0.3048)
			(stroke
				(width 0.1)
				(type default)
			)
			(layer "B.Fab")
		)
		(fp_line
			(start -0.120396 0.2794)
			(end 0.12065 0.2794)
			(stroke
				(width 0.1)
				(type default)
			)
			(layer "B.Fab")
		)
		(fp_line
			(start 0.67945 0.3048)
			(end 0.67945 -0.305054)
			(stroke
				(width 0.1)
				(type default)
			)
			(layer "B.Fab")
		)
		(fp_line
			(start 0.12065 0.3048)
			(end 0.67945 0.3048)
			(stroke
				(width 0.1)
				(type default)
			)
			(layer "B.Fab")
		)
		(fp_line
			(start -0.120396 0.3048)
			(end -0.120396 0.2794)
			(stroke
				(width 0.1)
				(type default)
			)
			(layer "B.Fab")
		)
		(fp_line
			(start -0.67945 0.3048)
			(end -0.120396 0.3048)
			(stroke
				(width 0.1)
				(type default)
			)
			(layer "B.Fab")
		)
		(pad "1" smd circle
			(at 0.40005 0 270)
			(size 0 0)
			(layers "B.Cu" "B.Mask" "B.Paste")
			(net "P3V3_AUX")
		)
		(pad "2" smd circle
			(at -0.40005 0 270)
			(size 0 0)
			(layers "B.Cu" "B.Mask" "B.Paste")
			(net "GPU_FPGA_THERM_OVERT_N")
		)
	)
	(footprint ""
		(layer "B.Cu")
		(at 112.054386 -264.862564)
		(property "Reference" "C3905"
			(at 0 0 0)
			(layer "B.SilkS")
			(hide yes)
			(effects
				(font
					(size 1.27 1.27)
				)
				(justify mirror)
			)
		)
		(property "Value" ""
			(at 0 0 0)
			(layer "B.Fab")
			(effects
				(font
					(size 1.27 1.27)
				)
				(justify mirror)
			)
		)
		(duplicate_pad_numbers_are_jumpers no)
		(fp_line
			(start -0.7874 -0.4064)
			(end -0.7874 0.4064)
			(stroke
				(width 0.1524)
				(type default)
			)
			(layer "B.SilkS")
		)
		(fp_line
			(start -0.7874 0.4064)
			(end 0.7874 0.4064)
			(stroke
				(width 0.1524)
				(type default)
			)
			(layer "B.SilkS")
		)
		(fp_line
			(start 0.7874 -0.4064)
			(end -0.7874 -0.4064)
			(stroke
				(width 0.1524)
				(type default)
			)
			(layer "B.SilkS")
		)
		(fp_line
			(start 0.7874 0.4064)
			(end 0.7874 -0.4064)
			(stroke
				(width 0.1524)
				(type default)
			)
			(layer "B.SilkS")
		)
		(fp_line
			(start -0.67945 -0.3048)
			(end -0.67945 0.3048)
			(stroke
				(width 0.1)
				(type default)
			)
			(layer "B.Fab")
		)
		(fp_line
			(start -0.67945 0.3048)
			(end -0.120396 0.3048)
			(stroke
				(width 0.1)
				(type default)
			)
			(layer "B.Fab")
		)
		(fp_line
			(start -0.12065 -0.3048)
			(end -0.67945 -0.3048)
			(stroke
				(width 0.1)
				(type default)
			)
			(layer "B.Fab")
		)
		(fp_line
			(start -0.12065 -0.2794)
			(end -0.12065 -0.3048)
			(stroke
				(width 0.1)
				(type default)
			)
			(layer "B.Fab")
		)
		(fp_line
			(start -0.120396 0.2794)
			(end 0.12065 0.2794)
			(stroke
				(width 0.1)
				(type default)
			)
			(layer "B.Fab")
		)
		(fp_line
			(start -0.120396 0.3048)
			(end -0.120396 0.2794)
			(stroke
				(width 0.1)
				(type default)
			)
			(layer "B.Fab")
		)
		(fp_line
			(start 0.12065 -0.305054)
			(end 0.12065 -0.2794)
			(stroke
				(width 0.1)
				(type default)
			)
			(layer "B.Fab")
		)
		(fp_line
			(start 0.12065 -0.2794)
			(end -0.12065 -0.2794)
			(stroke
				(width 0.1)
				(type default)
			)
			(layer "B.Fab")
		)
		(fp_line
			(start 0.12065 0.2794)
			(end 0.12065 0.3048)
			(stroke
				(width 0.1)
				(type default)
			)
			(layer "B.Fab")
		)
		(fp_line
			(start 0.12065 0.3048)
			(end 0.67945 0.3048)
			(stroke
				(width 0.1)
				(type default)
			)
			(layer "B.Fab")
		)
		(fp_line
			(start 0.67945 -0.305054)
			(end 0.12065 -0.305054)
			(stroke
				(width 0.1)
				(type default)
			)
			(layer "B.Fab")
		)
		(fp_line
			(start 0.67945 0.3048)
			(end 0.67945 -0.305054)
			(stroke
				(width 0.1)
				(type default)
			)
			(layer "B.Fab")
		)
		(pad "1" smd circle
			(at 0.40005 0 180)
			(size 0 0)
			(layers "B.Cu" "B.Mask" "B.Paste")
			(net "PVDD11_S3_P1")
		)
		(pad "2" smd circle
			(at -0.40005 0 180)
			(size 0 0)
			(layers "B.Cu" "B.Mask" "B.Paste")
			(net "GND")
		)
	)
	(footprint ""
		(layer "B.Cu")
		(at 354.046028 -396.393162 -90)
		(property "Reference" "C614"
			(at 0 0 90)
			(layer "B.SilkS")
			(hide yes)
			(effects
				(font
					(size 1.27 1.27)
				)
				(justify mirror)
			)
		)
		(property "Value" ""
			(at 0 0 90)
			(layer "B.Fab")
			(effects
				(font
					(size 1.27 1.27)
				)
				(justify mirror)
			)
		)
		(duplicate_pad_numbers_are_jumpers no)
		(fp_line
			(start -0.299974 0.150114)
			(end 0.299974 0.150114)
			(stroke
				(width 0.1)
				(type default)
			)
			(layer "B.Fab")
		)
		(fp_line
			(start 0.299974 0.150114)
			(end 0.299974 -0.150114)
			(stroke
				(width 0.1)
				(type default)
			)
			(layer "B.Fab")
		)
		(fp_line
			(start -0.299974 -0.150114)
			(end -0.299974 0.150114)
			(stroke
				(width 0.1)
				(type default)
			)
			(layer "B.Fab")
		)
		(fp_line
			(start 0.299974 -0.150114)
			(end -0.299974 -0.150114)
			(stroke
				(width 0.1)
				(type default)
			)
			(layer "B.Fab")
		)
		(pad "1" smd rect
			(at 0.2667 0 90)
			(size 0.3048 0.381)
			(layers "B.Cu" "B.Mask" "B.Paste")
			(net "P0V9_CPU0_RT1_2A")
		)
		(pad "2" smd rect
			(at -0.2667 0 90)
			(size 0.3048 0.381)
			(layers "B.Cu" "B.Mask" "B.Paste")
			(net "GND")
		)
	)
	(footprint ""
		(layer "B.Cu")
		(at 295.402 -426.339 180)
		(property "Reference" "R835"
			(at 0 0 0)
			(layer "B.SilkS")
			(hide yes)
			(effects
				(font
					(size 1.27 1.27)
				)
				(justify mirror)
			)
		)
		(property "Value" ""
			(at 0 0 0)
			(layer "B.Fab")
			(effects
				(font
					(size 1.27 1.27)
				)
				(justify mirror)
			)
		)
		(duplicate_pad_numbers_are_jumpers no)
		(fp_line
			(start 0.32512 0.175006)
			(end 0.32512 -0.175006)
			(stroke
				(width 0.1)
				(type default)
			)
			(layer "B.Fab")
		)
		(fp_line
			(start 0.32512 -0.175006)
			(end -0.32512 -0.175006)
			(stroke
				(width 0.1)
				(type default)
			)
			(layer "B.Fab")
		)
		(fp_line
			(start -0.32512 0.175006)
			(end 0.32512 0.175006)
			(stroke
				(width 0.1)
				(type default)
			)
			(layer "B.Fab")
		)
		(fp_line
			(start -0.32512 -0.175006)
			(end -0.32512 0.175006)
			(stroke
				(width 0.1)
				(type default)
			)
			(layer "B.Fab")
		)
		(pad "1" smd rect
			(at 0.2667 0)
			(size 0.3048 0.381)
			(layers "B.Cu" "B.Mask" "B.Paste")
			(net "P1V8_CPU0_RT_1D")
		)
		(pad "2" smd rect
			(at -0.2667 0 180)
			(size 0.3048 0.381)
			(layers "B.Cu" "B.Mask" "B.Paste")
			(net "SMB_RT_CPU0_P0_ROM_R_SCL")
		)
	)
	(footprint ""
		(layer "B.Cu")
		(at 413.136842 -416.899344 90)
		(property "Reference" "C6623"
			(at 0 0 90)
			(layer "B.SilkS")
			(hide yes)
			(effects
				(font
					(size 1.27 1.27)
				)
				(justify mirror)
			)
		)
		(property "Value" ""
			(at 0 0 90)
			(layer "B.Fab")
			(effects
				(font
					(size 1.27 1.27)
				)
				(justify mirror)
			)
		)
		(duplicate_pad_numbers_are_jumpers no)
		(fp_line
			(start 0.299974 -0.150114)
			(end -0.299974 -0.150114)
			(stroke
				(width 0.1)
				(type default)
			)
			(layer "B.Fab")
		)
		(fp_line
			(start -0.299974 -0.150114)
			(end -0.299974 0.150114)
			(stroke
				(width 0.1)
				(type default)
			)
			(layer "B.Fab")
		)
		(fp_line
			(start 0.299974 0.150114)
			(end 0.299974 -0.150114)
			(stroke
				(width 0.1)
				(type default)
			)
			(layer "B.Fab")
		)
		(fp_line
			(start -0.299974 0.150114)
			(end 0.299974 0.150114)
			(stroke
				(width 0.1)
				(type default)
			)
			(layer "B.Fab")
		)
		(pad "1" smd rect
			(at 0.2667 0 270)
			(size 0.3048 0.381)
			(layers "B.Cu" "B.Mask" "B.Paste")
			(net "P5E_CPU0_P3_TX_BUF_C_DP<13>")
		)
		(pad "2" smd rect
			(at -0.2667 0 270)
			(size 0.3048 0.381)
			(layers "B.Cu" "B.Mask" "B.Paste")
			(net "P5E_CPU0_P3_TX_BUF_DP<13>")
		)
	)
	(footprint ""
		(layer "B.Cu")
		(at 86.652354 -191.358012 90)
		(property "Reference" "PC283_1"
			(at 0 0 90)
			(layer "B.SilkS")
			(hide yes)
			(effects
				(font
					(size 1.27 1.27)
				)
				(justify mirror)
			)
		)
		(property "Value" ""
			(at 0 0 90)
			(layer "B.Fab")
			(effects
				(font
					(size 1.27 1.27)
				)
				(justify mirror)
			)
		)
		(duplicate_pad_numbers_are_jumpers no)
		(fp_line
			(start 1.524 -0.762)
			(end -1.524 -0.762)
			(stroke
				(width 0.1524)
				(type default)
			)
			(layer "B.SilkS")
		)
		(fp_line
			(start -1.524 -0.762)
			(end -1.524 0.762)
			(stroke
				(width 0.1524)
				(type default)
			)
			(layer "B.SilkS")
		)
		(fp_line
			(start 1.524 0.762)
			(end 1.524 -0.762)
			(stroke
				(width 0.1524)
				(type default)
			)
			(layer "B.SilkS")
		)
		(fp_line
			(start -1.524 0.762)
			(end 1.524 0.762)
			(stroke
				(width 0.1524)
				(type default)
			)
			(layer "B.SilkS")
		)
		(fp_line
			(start 1.1049 -0.724916)
			(end 1.1049 0.724916)
			(stroke
				(width 0.1)
				(type default)
			)
			(layer "B.Fab")
		)
		(fp_line
			(start -1.1049 -0.724916)
			(end 1.1049 -0.724916)
			(stroke
				(width 0.1)
				(type default)
			)
			(layer "B.Fab")
		)
		(fp_line
			(start 1.1049 0.724916)
			(end -1.1049 0.724916)
			(stroke
				(width 0.1)
				(type default)
			)
			(layer "B.Fab")
		)
		(fp_line
			(start -1.1049 0.724916)
			(end -1.1049 -0.724916)
			(stroke
				(width 0.1)
				(type default)
			)
			(layer "B.Fab")
		)
		(pad "1" smd rect
			(at 0.889 0 90)
			(size 1.016 1.27)
			(layers "B.Cu" "B.Mask" "B.Paste")
			(net "PVDDCR_CPU0_P1")
		)
		(pad "2" smd rect
			(at -0.889 0 90)
			(size 1.016 1.27)
			(layers "B.Cu" "B.Mask" "B.Paste")
			(net "GND")
		)
	)
)
